G04 ================== begin FILE IDENTIFICATION RECORD ==================*
G04 Layout Name:  9052_F0T_PDB_Converter_Brick_F_V03_1208_1600.brd*
G04 Film Name:    smt*
G04 File Format:  Gerber RS274X*
G04 File Origin:  Cadence Allegro 17.2-S081*
G04 Origin Date:  Wed Dec 21 09:54:58 2022*
G04 *
G04 Layer:  DRAWING FORMAT/TITLE_BLOCK_A*
G04 Layer:  DRAWING FORMAT/TITLE_BLOCK*
G04 Layer:  VIA CLASS/SOLDERMASK_TOP*
G04 Layer:  PIN/SOLDERMASK_TOP*
G04 Layer:  PACKAGE GEOMETRY/SOLDERMASK_TOP*
G04 Layer:  MANUFACTURING/PHOTOPLOT_OUTLINE*
G04 Layer:  DRAWING FORMAT/TITLE_DATA_SMT*
G04 Layer:  BOARD GEOMETRY/SOLDERMASK_TOP*
G04 *
G04 Offset:    (0.00 0.00)*
G04 Mirror:    No*
G04 Mode:      Positive*
G04 Rotation:  0*
G04 FullContactRelief:  No*
G04 UndefLineWidth:     6.00*
G04 ================== end FILE IDENTIFICATION RECORD ====================*
%FSLAX25Y25*MOIN*%
%IR0*IPPOS*OFA0.00000B0.00000*MIA0B0*SFA1.00000B1.00000*%
%ADD18R,.103X.071*%
%ADD81R,.126X.056*%
%ADD74C,.07*%
%ADD17C,.034*%
%ADD90R,.063X.138*%
%ADD12C,.062*%
%ADD13C,.054*%
%ADD46C,.064*%
%ADD42C,.056*%
%ADD10O,1.264X.398*%
%ADD91R,.134X.099*%
%ADD39C,.066*%
%ADD65C,.085*%
%ADD73R,.07X.07*%
%ADD49C,.06415*%
%ADD43C,.097*%
%ADD14R,.054X.054*%
%ADD47R,.064X.064*%
%ADD64R,.0888X.134*%
%ADD38R,.066X.066*%
%AMMACRO60*
4,1,5,.01578,-.00692,
-.01067,-.00692,
-.01578,-.00181,
-.01578,.00692,
.01578,.00692,
.01578,-.00692,
0.0*
%
%ADD60MACRO60*%
%AMMACRO26*
4,1,5,-.01362,-.00692,
-.01873,-.00181,
-.01873,.00692,
.01873,.00692,
.01873,-.00692,
-.01362,-.00692,
0.0*
%
%ADD26MACRO26*%
%AMMACRO55*
4,1,5,-.00692,-.01578,
-.00692,.01067,
-.00181,.01578,
.00692,.01578,
.00692,-.01578,
-.00692,-.01578,
0.0*
%
%ADD55MACRO55*%
%ADD50R,.06415X.06415*%
%ADD48R,.097X.097*%
%AMMACRO30*
4,1,28,-.00589,-.01192,
-.006913,-.011842,
-.007907,-.011587,
-.008842,-.011163,
-.009688,-.010584,
-.010422,-.009866,
-.011019,-.009032,
-.011463,-.008107,
-.011739,-.007119,
-.01184,-.006097,
-.01184,-.00603,
-.01184,.00148,
-.00948,.00148,
-.00948,.01191,
.00948,.01191,
.00948,.00148,
.01184,.00148,
.01184,-.00603,
.011751,-.007052,
.011486,-.008044,
.011053,-.008974,
.010465,-.009815,
.00974,-.010541,
.0089,-.01113,
.00797,-.011564,
.006979,-.01183,
.005957,-.01192,
.00589,-.01192,
-.00589,-.01192,
0.0*
%
%ADD30MACRO30*%
%AMMACRO28*
4,1,28,-.01192,.00589,
-.011842,.006913,
-.011587,.007907,
-.011163,.008842,
-.010584,.009688,
-.009866,.010422,
-.009032,.011019,
-.008107,.011463,
-.007119,.011739,
-.006097,.01184,
-.00603,.01184,
.00148,.01184,
.00148,.00948,
.01191,.00948,
.01191,-.00948,
.00148,-.00948,
.00148,-.01184,
-.00603,-.01184,
-.007052,-.011751,
-.008044,-.011486,
-.008974,-.011053,
-.009815,-.010465,
-.010541,-.00974,
-.01113,-.0089,
-.011564,-.00797,
-.01183,-.006979,
-.01192,-.005957,
-.01192,-.00589,
-.01192,.00589,
0.0*
%
%ADD28MACRO28*%
%AMMACRO59*
4,1,5,.01578,-.00692,
-.01578,-.00692,
-.01578,.00181,
-.01067,.00692,
.01578,.00692,
.01578,-.00692,
0.0*
%
%ADD59MACRO59*%
%AMMACRO54*
4,1,5,-.00692,-.01578,
-.00692,.01578,
.00181,.01578,
.00692,.01067,
.00692,-.01578,
-.00692,-.01578,
0.0*
%
%ADD54MACRO54*%
%AMMACRO24*
4,1,8,-.02661,.02021,
.0266,.02021,
.0266,-.02021,
.01276,-.02021,
.01276,.00637,
-.01277,.00637,
-.01277,-.02021,
-.02661,-.02021,
-.02661,.02021,
0.0*
%
%ADD24MACRO24*%
%AMMACRO29*
4,1,28,.0059,.01191,
.006923,.01183,
.007916,.011573,
.00885,.011148,
.009696,.010567,
.010428,.009849,
.011024,.009013,
.011466,.008088,
.011741,.007099,
.01184,.006078,
.01184,.00602,
.01184,-.00149,
.00948,-.00149,
.00948,-.01192,
-.00948,-.01192,
-.00948,-.00149,
-.01184,-.00149,
-.01184,.00602,
-.011751,.007042,
-.011486,.008033,
-.011053,.008964,
-.010465,.009805,
-.00974,.010531,
-.0089,.01112,
-.007971,.011554,
-.00698,.01182,
-.005958,.01191,
-.0059,.01191,
.0059,.01191,
0.0*
%
%ADD29MACRO29*%
%AMMACRO27*
4,1,28,.01191,-.0059,
.01183,-.006923,
.011573,-.007916,
.011148,-.00885,
.010567,-.009696,
.009849,-.010428,
.009013,-.011024,
.008088,-.011466,
.007099,-.011741,
.006078,-.01184,
.00602,-.01184,
-.00149,-.01184,
-.00149,-.00948,
-.01192,-.00948,
-.01192,.00948,
-.00149,.00948,
-.00149,.01184,
.00602,.01184,
.007042,.011751,
.008033,.011486,
.008964,.011053,
.009805,.010465,
.010531,.00974,
.01112,.0089,
.011554,.007971,
.01182,.00698,
.01191,.005958,
.01191,.0059,
.01191,-.0059,
0.0*
%
%ADD27MACRO27*%
%ADD67R,.201X.12*%
%ADD72R,.12X.201*%
%ADD85R,.103X.134*%
%ADD58R,.04X.014*%
%ADD86R,.114X.224*%
%ADD19R,.024X.022*%
%ADD77R,.032X.015*%
%ADD33R,.022X.024*%
%ADD93R,.014X.024*%
%ADD87O,.037X.014*%
%AMMACRO84*
4,1,8,.16834,-.21066,
.07576,-.21066,
.07576,-.14964,
-.16834,-.14964,
-.16834,.14964,
.07576,.14964,
.07576,.21066,
.16834,.21066,
.16834,-.21066,
0.0*
%
%ADD84MACRO84*%
%ADD76R,.015X.032*%
%ADD94R,.13X.274*%
%ADD88O,.014X.037*%
%ADD79R,.034X.015*%
%ADD92R,.139X.132*%
%ADD78R,.015X.034*%
%AMMACRO75*
4,1,5,-.07385,-.1083,
-.07385,.09335,
-.0589,.1083,
.07385,.1083,
.07385,-.1083,
-.07385,-.1083,
0.0*
%
%ADD75MACRO75*%
%ADD53R,.036X.032*%
%ADD34R,.054X.014*%
%ADD25R,.036X.014*%
%ADD66R,.032X.028*%
%ADD35R,.014X.036*%
%ADD20R,.032X.036*%
%ADD80R,.019X.05*%
%ADD69R,.028X.032*%
%ADD62R,.056X.014*%
%ADD16C,.241*%
%ADD89C,.404*%
%ADD82R,.036X.026*%
%ADD71R,.066X.05*%
%ADD52R,.054X.044*%
%ADD44C,.26*%
%ADD11C,.107*%
%ADD51R,.044X.054*%
%ADD37R,.05X.066*%
%ADD40C,.118*%
%ADD36C,.127*%
%ADD21C,.145*%
%ADD70R,.067X.044*%
%ADD95C,.319*%
%ADD68R,.044X.067*%
%ADD15C,.176*%
%ADD83R,.058X.048*%
%ADD45R,.048X.058*%
%ADD41R,.093X.089*%
%AMMACRO63*
4,1,5,-.01578,.00692,
.01067,.00692,
.01578,.00181,
.01578,-.00692,
-.01578,-.00692,
-.01578,.00692,
0.0*
%
%ADD63MACRO63*%
%AMMACRO57*
4,1,5,.00692,.01578,
.00692,-.01067,
.00181,-.01578,
-.00692,-.01578,
-.00692,.01578,
.00692,.01578,
0.0*
%
%ADD57MACRO57*%
%AMMACRO32*
4,1,28,.00589,.01192,
.006913,.011842,
.007907,.011587,
.008842,.011163,
.009688,.010584,
.010422,.009866,
.011019,.009032,
.011463,.008107,
.011739,.007119,
.01184,.006097,
.01184,.00603,
.01184,-.00148,
.00948,-.00148,
.00948,-.01191,
-.00948,-.01191,
-.00948,-.00148,
-.01184,-.00148,
-.01184,.00603,
-.011751,.007052,
-.011486,.008044,
-.011053,.008974,
-.010465,.009815,
-.00974,.010541,
-.0089,.01113,
-.00797,.011564,
-.006979,.01183,
-.005957,.01192,
-.00589,.01192,
.00589,.01192,
0.0*
%
%ADD32MACRO32*%
%AMMACRO23*
4,1,28,.01192,-.00589,
.011842,-.006913,
.011587,-.007907,
.011163,-.008842,
.010584,-.009688,
.009866,-.010422,
.009032,-.011019,
.008107,-.011463,
.007119,-.011739,
.006097,-.01184,
.00603,-.01184,
-.00148,-.01184,
-.00148,-.00948,
-.01191,-.00948,
-.01191,.00948,
-.00148,.00948,
-.00148,.01184,
.00603,.01184,
.007052,.011751,
.008044,.011486,
.008974,.011053,
.009815,.010465,
.010541,.00974,
.01113,.0089,
.011564,.00797,
.01183,.006979,
.01192,.005957,
.01192,.00589,
.01192,-.00589,
0.0*
%
%ADD23MACRO23*%
%AMMACRO61*
4,1,5,-.01578,.00692,
.01578,.00692,
.01578,-.00181,
.01067,-.00692,
-.01578,-.00692,
-.01578,.00692,
0.0*
%
%ADD61MACRO61*%
%AMMACRO56*
4,1,5,.00692,.01578,
.00692,-.01578,
-.00181,-.01578,
-.00692,-.01067,
-.00692,.01578,
.00692,.01578,
0.0*
%
%ADD56MACRO56*%
%AMMACRO31*
4,1,28,-.0059,-.01191,
-.006923,-.01183,
-.007916,-.011573,
-.00885,-.011148,
-.009696,-.010567,
-.010428,-.009849,
-.011024,-.009013,
-.011466,-.008088,
-.011741,-.007099,
-.01184,-.006078,
-.01184,-.00602,
-.01184,.00149,
-.00948,.00149,
-.00948,.01192,
.00948,.01192,
.00948,.00149,
.01184,.00149,
.01184,-.00602,
.011751,-.007042,
.011486,-.008033,
.011053,-.008964,
.010465,-.009805,
.00974,-.010531,
.0089,-.01112,
.007971,-.011554,
.00698,-.01182,
.005958,-.01191,
.0059,-.01191,
-.0059,-.01191,
0.0*
%
%ADD31MACRO31*%
%AMMACRO22*
4,1,28,-.01191,.0059,
-.01183,.006923,
-.011573,.007916,
-.011148,.00885,
-.010567,.009696,
-.009849,.010428,
-.009013,.011024,
-.008088,.011466,
-.007099,.011741,
-.006078,.01184,
-.00602,.01184,
.00149,.01184,
.00149,.00948,
.01192,.00948,
.01192,-.00948,
.00149,-.00948,
.00149,-.01184,
-.00602,-.01184,
-.007042,-.011751,
-.008033,-.011486,
-.008964,-.011053,
-.009805,-.010465,
-.010531,-.00974,
-.01112,-.0089,
-.011554,-.007971,
-.01182,-.00698,
-.01191,-.005958,
-.01191,-.0059,
-.01191,.0059,
0.0*
%
%ADD22MACRO22*%
%ADD96C,.02*%
%ADD97C,.006*%
G75*
%LPD*%
G75*
G36*
G01X206900Y20500D02*
G03I-5900J0D01*
G37*
G36*
G01X898010Y81122D02*
G03I-5900J0D01*
G37*
G36*
G01X1182715Y555392D02*
G03I-5900J0D01*
G37*
G54D10*
X74804Y47244D03*
Y535433D03*
X468504Y47244D03*
X862205D03*
X945193Y228000D03*
X987193Y542500D03*
G54D11*
X19922Y214173D03*
Y367716D03*
G54D20*
X152200Y241200D03*
Y235400D03*
X147000Y241200D03*
Y235400D03*
X1064500Y276242D03*
Y270442D03*
Y323742D03*
Y317942D03*
Y359642D03*
Y365442D03*
Y418742D03*
Y412942D03*
Y466242D03*
Y460442D03*
Y513742D03*
Y507942D03*
G54D21*
X175000Y100500D03*
X877510Y558620D03*
X964460Y16950D03*
G54D30*
X170040Y242347D03*
X710000Y39017D03*
X706000Y56517D03*
X803500Y262017D03*
X792354Y262126D03*
X782354D03*
X1041500Y186017D03*
X1091000Y94017D03*
X1095100D03*
X1108500Y139017D03*
X1110000Y192517D03*
X1118000D03*
X1106000D03*
X1114000D03*
X1122000D03*
X1133000D03*
G54D12*
X38780Y232598D03*
Y239291D03*
Y252598D03*
Y259291D03*
Y272598D03*
Y279291D03*
Y292598D03*
Y299291D03*
X48780Y232598D03*
Y239291D03*
Y252598D03*
Y259291D03*
Y272598D03*
Y279291D03*
Y292598D03*
Y299291D03*
G54D22*
X178356Y216830D03*
X687016Y36500D03*
Y32500D03*
X698616Y57800D03*
X1019516Y98000D03*
Y118000D03*
X1041070Y131267D03*
Y139267D03*
Y135267D03*
X1048070Y131267D03*
X1096516Y188000D03*
X1093016Y173500D03*
X1096516Y179500D03*
X1096484Y183599D03*
X1123016Y138457D03*
X1177927Y346750D03*
X1178016Y489250D03*
G54D31*
X166040Y242346D03*
X710000Y46516D03*
X787354Y262125D03*
X1048000Y135516D03*
X1067000Y186016D03*
X1053500D03*
X1058000D03*
X1062500D03*
X1104500Y139016D03*
X1112500D03*
G54D40*
X201000Y20500D03*
X892110Y81122D03*
X1176815Y555392D03*
G54D13*
X33780Y334724D03*
Y324724D03*
X38780Y319724D03*
Y329724D03*
Y339724D03*
X33780Y344724D03*
X38780Y349724D03*
X48780Y319724D03*
Y329724D03*
Y339724D03*
X43780Y314724D03*
Y324724D03*
Y334724D03*
X48780Y349724D03*
X43780Y344724D03*
G54D23*
X181323Y216830D03*
X689983Y36500D03*
Y32500D03*
X701583Y57800D03*
X1022483Y98000D03*
Y118000D03*
X1044037Y131267D03*
X1051037D03*
X1044037Y139267D03*
Y135267D03*
X1099483Y188000D03*
X1095983Y173500D03*
X1099483Y179500D03*
X1099451Y183599D03*
X1125983Y138457D03*
X1180894Y346750D03*
X1180983Y489250D03*
G54D32*
X166040Y245313D03*
X710000Y49483D03*
X787354Y265092D03*
X1048000Y138483D03*
X1067000Y188983D03*
X1053500D03*
X1058000D03*
X1062500D03*
X1104500Y141983D03*
X1112500D03*
G54D41*
X197400Y214054D03*
Y233346D03*
G54D50*
X296752Y159685D03*
X832559Y149408D03*
X1226024Y286929D03*
G54D14*
X33780Y314724D03*
G54D15*
X60630Y99724D03*
Y482205D03*
X108858Y99724D03*
Y482205D03*
G54D51*
X293500Y204500D03*
X286500D03*
X293500Y196500D03*
X286500D03*
X329500Y204500D03*
Y196500D03*
X315000Y204500D03*
X308000D03*
X315000Y196500D03*
X308000D03*
X358000Y204500D03*
X351000D03*
X358000Y196500D03*
X351000D03*
X336500Y204500D03*
Y196500D03*
X379500Y204500D03*
X372500D03*
X379500Y197000D03*
X372500D03*
X422500Y204500D03*
X415500D03*
X422500Y197000D03*
X415500D03*
X401000Y204500D03*
X394000D03*
X401000Y197000D03*
X394000D03*
X594000Y204000D03*
Y196500D03*
X622500D03*
X615500D03*
X622500Y204000D03*
X615500D03*
X601000D03*
Y196500D03*
X658500Y204000D03*
Y196500D03*
X644000Y204000D03*
X637000D03*
X644000Y196500D03*
X637000D03*
X687000Y204000D03*
X680000D03*
X687000Y196500D03*
X680000D03*
X665500Y204000D03*
Y196500D03*
X708490Y204000D03*
X701490D03*
X708490Y196500D03*
X701490D03*
X729990Y204000D03*
X722990D03*
X729990Y196500D03*
X722990D03*
X758000Y43000D03*
X751000D03*
X758000Y34500D03*
X751000D03*
X758000Y60000D03*
X751000D03*
X758000Y51500D03*
X751000D03*
X1144585Y145913D03*
X1151585D03*
G54D33*
X162132Y249140D03*
X158982D03*
X162132Y245160D03*
X158982D03*
X239575Y243000D03*
X236425D03*
X239575Y247500D03*
X236425D03*
X395575Y242500D03*
X392425D03*
X395575Y247000D03*
X392425D03*
X549075Y243500D03*
X545925D03*
X549075Y248000D03*
X545925D03*
X645575Y33000D03*
X642425D03*
X645575Y37000D03*
X642425D03*
X706556Y243500D03*
X703406D03*
X706556Y248000D03*
X703406D03*
X1108590Y224241D03*
X1111740D03*
D03*
X1114890D03*
X1111656Y231741D03*
X1114806D03*
X1111656D03*
X1108506D03*
G54D24*
X164101Y216997D03*
G54D60*
X703740Y43363D03*
G54D42*
X208071Y267204D03*
X200197D03*
X215945D03*
X231693D03*
X223819D03*
X239567D03*
X247441D03*
X357677D03*
X365551D03*
X373425D03*
X389173D03*
X381299D03*
X404921D03*
X397047D03*
X523032D03*
X515158D03*
X530906D03*
X538780D03*
X546654D03*
X562402D03*
X554528D03*
X680513D03*
X672639D03*
X688387D03*
X704135D03*
X696261D03*
X712009D03*
X719883D03*
G54D61*
X696260Y43363D03*
G54D70*
X840000Y369701D03*
Y382299D03*
X1155000Y193201D03*
Y205799D03*
G54D52*
X653700Y52700D03*
Y45700D03*
X677400Y52700D03*
Y45700D03*
X685300Y52700D03*
Y45700D03*
X669500Y52700D03*
Y45700D03*
X661600Y52700D03*
Y45700D03*
X1130368Y228060D03*
X1121568Y224060D03*
Y232060D03*
G54D16*
X82795Y99724D03*
Y482205D03*
G54D25*
X158588Y218326D03*
Y220294D03*
Y222263D03*
Y224232D03*
Y226200D03*
Y228168D03*
Y230137D03*
Y232106D03*
Y234074D03*
X169612D03*
Y232106D03*
Y230137D03*
Y228168D03*
Y226200D03*
Y224232D03*
Y222263D03*
Y220294D03*
G54D34*
X164100Y232499D03*
Y228956D03*
Y225413D03*
Y221869D03*
G54D43*
X193819Y477204D03*
X223819D03*
X351299D03*
X381299D03*
X508780D03*
X538780D03*
X666261D03*
X696261D03*
G54D44*
X249252Y129685D03*
X529252D03*
X665059Y149408D03*
X980059D03*
X1226024Y174429D03*
Y399429D03*
G54D71*
X849000Y370200D03*
Y381800D03*
X867000Y370200D03*
Y381800D03*
X858000Y370200D03*
Y381800D03*
X876000Y370200D03*
Y381800D03*
X895000Y370200D03*
Y381800D03*
X885500Y370200D03*
Y381800D03*
X904500Y370200D03*
Y381800D03*
X914000Y370200D03*
Y381800D03*
X923500Y370200D03*
Y381800D03*
X933000Y370200D03*
Y381800D03*
X942500Y370200D03*
Y381800D03*
X952000Y370200D03*
Y381800D03*
X1025000Y131200D03*
Y142800D03*
X1068554Y127467D03*
Y139067D03*
X1161200Y160200D03*
Y171800D03*
X1140641Y205399D03*
Y193799D03*
G54D62*
X697441Y47300D03*
G54D80*
X1070715Y150749D03*
Y174785D03*
X1073274Y150749D03*
X1075834D03*
X1078393D03*
X1073274Y174785D03*
X1075834D03*
X1078393D03*
G54D35*
X162132Y235649D03*
X166068D03*
G54D53*
X641300Y45200D03*
X647100D03*
X1039100Y126500D03*
X1044900D03*
X1101400Y168500D03*
X1095600D03*
X1110100Y83000D03*
X1115900D03*
X1145635Y124913D03*
X1151535D03*
X1170600Y105500D03*
X1176400D03*
X1174311Y328750D03*
X1168511D03*
X1184511D03*
X1190311D03*
Y335750D03*
X1184511D03*
X1168511D03*
X1174311D03*
Y341750D03*
X1168511D03*
X1184511D03*
X1190311D03*
X1184600Y484250D03*
X1190400D03*
X1174400D03*
X1168600D03*
X1174400Y471250D03*
X1168600D03*
X1184600D03*
X1190400D03*
X1174400Y478250D03*
X1168600D03*
X1184600D03*
X1190400D03*
G54D26*
X169513Y218326D03*
G54D17*
X92110Y300900D03*
X85000Y307310D03*
X77770Y313960D03*
X106230Y287950D03*
X99810Y294370D03*
X144900Y224500D03*
X141664Y239573D03*
X178265Y247712D03*
X171374Y251923D03*
X660100Y39900D03*
X711500Y61300D03*
X792000Y358000D03*
X833500Y268575D03*
X816000Y270525D03*
X827602Y283500D03*
X836500Y302500D03*
X814050Y341450D03*
X819500Y318500D03*
X831750Y318250D03*
X813100Y368600D03*
X827000Y352500D03*
X843500Y268575D03*
X853500D03*
X845000Y303000D03*
X848500Y335800D03*
X840000Y337500D03*
Y363000D03*
Y345500D03*
X843843Y354342D03*
X849000Y399000D03*
X870000Y304525D03*
X880000D03*
X870000Y312788D03*
X880000Y312855D03*
X875000Y347273D03*
X905941Y320366D03*
X916260Y355000D03*
X923740Y345500D03*
X940000Y283800D03*
X935516Y361075D03*
X933357Y344843D03*
X933196Y353360D03*
X1028940Y182130D03*
X1034290Y197990D03*
X1050220Y126510D03*
X1053505Y144080D03*
X1053000Y136500D03*
X1064500Y166000D03*
X1059500Y175500D03*
X1054000Y181000D03*
X1066000Y175500D03*
X1062500Y181000D03*
X1091000Y89000D03*
X1094500Y103000D03*
X1077400Y141300D03*
X1115500Y97500D03*
X1121000Y94500D03*
X1127148Y147566D03*
X1118000Y146000D03*
X1106500Y155000D03*
X1105000Y147500D03*
X1112500Y151000D03*
X1105500Y161779D03*
X1110925Y187500D03*
X1110800Y170000D03*
X1131088Y186912D03*
X1108500Y176000D03*
X1105170Y182630D03*
X1153845Y161098D03*
X1158750Y144750D03*
X1137808Y187588D03*
X1135000Y220600D03*
X1136600Y228060D03*
X1189000Y248500D03*
Y266000D03*
X1190500Y420000D03*
Y402500D03*
X1230000Y458000D03*
X1248000D03*
G54D63*
X696260Y51237D03*
G54D45*
X241740Y237000D03*
X234260D03*
X390260Y236500D03*
X397740D03*
X551240Y237500D03*
X543760D03*
X708721D03*
X701241D03*
X1028294Y188767D03*
X1020814D03*
X1028294Y199267D03*
X1020814D03*
X1083440Y95400D03*
X1075960D03*
X1096260Y82500D03*
X1098740Y199500D03*
X1091260D03*
X1103740Y82500D03*
G54D36*
X178819Y277204D03*
X193819D03*
X253819D03*
X268819D03*
X336299D03*
X351299D03*
X411299D03*
X426299D03*
X493780D03*
X508780D03*
X568780D03*
X583780D03*
X651261D03*
X666261D03*
X726261D03*
X741261D03*
G54D72*
X861622Y513070D03*
X904200D03*
G54D27*
X181384Y224820D03*
X181324Y242330D03*
X162041Y241140D03*
X181324Y231330D03*
Y220830D03*
Y238330D03*
X704484Y32000D03*
X697484D03*
X697519Y36695D03*
X697484Y27000D03*
X704519Y36695D03*
X755984Y27500D03*
Y68500D03*
X1041584Y193700D03*
X1044038Y143267D03*
X1089484Y103000D03*
X1099952Y160413D03*
X1100016Y143144D03*
X1099984Y147500D03*
X1099952Y156099D03*
Y151856D03*
X1112984Y88000D03*
X1129652Y142556D03*
X1103484Y173500D03*
X1128977Y192756D03*
X1133184Y138457D03*
X1174984Y111500D03*
G54D54*
X700984Y41591D03*
G54D90*
X1138178Y166699D03*
G54D81*
X1076164Y250442D03*
Y270442D03*
Y297942D03*
Y317942D03*
Y345442D03*
Y365442D03*
Y392942D03*
Y412942D03*
Y440442D03*
Y487942D03*
Y460442D03*
Y507942D03*
G54D18*
X118126Y258500D03*
X133874D03*
G54D37*
X181839Y503500D03*
X170239D03*
X181839Y512500D03*
X170239D03*
X229839D03*
X218239D03*
X229839Y503500D03*
X218239D03*
X266239D03*
Y512500D03*
X277839Y503500D03*
Y512500D03*
X327719Y503500D03*
Y512500D03*
X339319Y503500D03*
Y512500D03*
X387319D03*
X375719D03*
X387319Y503500D03*
X375719D03*
X435319D03*
X423719D03*
X435319Y512500D03*
X423719D03*
X496800D03*
X485200D03*
X496800Y503500D03*
X485200D03*
X533200D03*
Y512500D03*
X544800Y503500D03*
Y512500D03*
X592800D03*
X581200D03*
X592800Y503500D03*
X581200D03*
X654281Y512500D03*
X642681D03*
X654281Y503500D03*
X642681D03*
X702281Y512500D03*
X690681D03*
X702281Y503500D03*
X690681D03*
X738681Y512500D03*
Y503500D03*
X750281Y512500D03*
Y503500D03*
G54D82*
X1100276Y93760D03*
Y101240D03*
X1109724D03*
Y97500D03*
Y93760D03*
G54D19*
X153180Y215785D03*
Y218935D03*
X141840Y234905D03*
Y231755D03*
X181271Y212651D03*
Y209501D03*
X691400Y50875D03*
Y47725D03*
G54D28*
X178417Y224820D03*
X178357Y242330D03*
X159074Y241140D03*
X178357Y231330D03*
Y220830D03*
Y238330D03*
X701517Y32000D03*
X694517D03*
X694552Y36695D03*
X694517Y27000D03*
X701552Y36695D03*
X753017Y27500D03*
Y68500D03*
X1041071Y143267D03*
X1038617Y193700D03*
X1086517Y103000D03*
X1096985Y160413D03*
X1097049Y143144D03*
X1097017Y147500D03*
X1096985Y156099D03*
Y151856D03*
X1100517Y173500D03*
X1110017Y88000D03*
X1130217Y138457D03*
X1126685Y142556D03*
X1126010Y192756D03*
X1172017Y111500D03*
G54D55*
X699016Y41591D03*
G54D64*
X717985Y51000D03*
X741015D03*
G54D73*
X1011000Y98000D03*
X1151000Y90400D03*
G54D91*
X1183561Y130467D03*
Y156451D03*
G54D46*
X268000Y220315D03*
X312500D03*
X357000D03*
X428500D03*
X472500D03*
X516500D03*
X578500D03*
X622500D03*
X666500D03*
X735981D03*
X779981D03*
X823981D03*
G54D56*
X699016Y53009D03*
G54D83*
X1089772Y132065D03*
Y139545D03*
X1132941Y131996D03*
Y124516D03*
X1123441Y131996D03*
Y124516D03*
X1152587Y131678D03*
Y139158D03*
X1166000Y140760D03*
Y148240D03*
G54D92*
X1183100Y176094D03*
Y212906D03*
G54D29*
X170040Y245314D03*
X710000Y41984D03*
X706000Y59484D03*
X803500Y264984D03*
X792354Y265093D03*
X782354D03*
X1041500Y188984D03*
X1091000Y96984D03*
X1095100D03*
X1108500Y141984D03*
X1110000Y195484D03*
X1118000D03*
X1106000D03*
X1114000D03*
X1122000D03*
X1133000D03*
G54D38*
X165539Y539000D03*
X213539D03*
X261539D03*
X323019D03*
X371019D03*
X419019D03*
X480500D03*
X528500D03*
X576500D03*
X637981D03*
X685981D03*
X733981D03*
G54D47*
X268000Y240000D03*
X312500D03*
X357000D03*
X428500D03*
X472500D03*
X516500D03*
X578500D03*
X622500D03*
X666500D03*
X735981D03*
X779981D03*
X823981D03*
G54D65*
X753314Y607542D03*
X766498Y602542D03*
X753420Y635687D03*
X766604Y630687D03*
X766498Y612542D03*
X766604Y640687D03*
X1096017Y607542D03*
X1082833Y602542D03*
Y612542D03*
X1096017Y635687D03*
X1082833Y630687D03*
Y640687D03*
G54D74*
X1011000Y118000D03*
Y108000D03*
X1161000Y90400D03*
X1171000D03*
G54D57*
X700984Y53009D03*
G54D66*
X797854Y262239D03*
Y265979D03*
X809500Y262130D03*
Y265870D03*
G54D75*
X1041999Y162767D03*
G54D84*
X1116814Y260442D03*
Y307942D03*
Y355442D03*
Y402942D03*
Y450442D03*
Y497942D03*
G54D93*
X1176593Y307942D03*
X1182709D03*
X1176682Y450442D03*
X1182798D03*
G54D48*
X253819Y477204D03*
X411299D03*
X568780D03*
X726261D03*
G54D39*
X185224Y539000D03*
X233224D03*
X281224D03*
X342704D03*
X390704D03*
X438704D03*
X500185D03*
X548185D03*
X596185D03*
X657666D03*
X705666D03*
X753666D03*
G54D94*
X1170793Y307942D03*
X1188509D03*
X1170882Y450442D03*
X1188598D03*
G54D76*
X1027727Y149281D03*
Y176253D03*
X1049381Y149281D03*
Y176253D03*
G54D58*
X703346Y49268D03*
Y45332D03*
Y47300D03*
X696654Y45332D03*
Y49268D03*
G54D85*
X1077614Y545500D03*
X1104386D03*
G54D67*
X807315Y424566D03*
Y467144D03*
X863917Y424566D03*
Y467144D03*
G54D49*
X296752Y129685D03*
Y139685D03*
Y149685D03*
X331752Y129685D03*
X306752D03*
X331752Y139685D03*
Y149685D03*
Y159685D03*
X306752Y139685D03*
Y149685D03*
Y159685D03*
X341752Y129685D03*
Y139685D03*
Y149685D03*
Y159685D03*
X376752Y129685D03*
X366752D03*
X376752Y139685D03*
Y149685D03*
Y159685D03*
X366752Y139685D03*
Y149685D03*
Y159685D03*
X411752Y129685D03*
X401752D03*
X411752Y139685D03*
Y149685D03*
Y159685D03*
X401752Y139685D03*
Y149685D03*
Y159685D03*
X446752Y129685D03*
X436752D03*
X446752Y139685D03*
Y149685D03*
Y159685D03*
X436752Y139685D03*
Y149685D03*
Y159685D03*
X481752Y129685D03*
X471752D03*
X481752Y139685D03*
Y149685D03*
Y159685D03*
X471752Y139685D03*
Y149685D03*
Y159685D03*
X712559Y129408D03*
Y119408D03*
Y149408D03*
Y139408D03*
X722559Y129408D03*
Y119408D03*
X747559Y129408D03*
Y119408D03*
X722559Y149408D03*
Y139408D03*
X747559Y149408D03*
Y139408D03*
X757559Y129408D03*
Y119408D03*
Y149408D03*
Y139408D03*
X782559Y129408D03*
Y119408D03*
X792559Y129408D03*
Y119408D03*
X782559Y149408D03*
Y139408D03*
X792559Y149408D03*
Y139408D03*
X812559Y119408D03*
Y129408D03*
X822559Y119408D03*
Y129408D03*
X832559Y119408D03*
Y129408D03*
X812559Y139408D03*
Y149408D03*
X822559Y139408D03*
Y149408D03*
X832559Y139408D03*
X852559Y129408D03*
Y119408D03*
X862559Y129408D03*
Y119408D03*
X852559Y149408D03*
Y139408D03*
X862559Y149408D03*
Y139408D03*
X887559Y129408D03*
Y119408D03*
Y149408D03*
Y139408D03*
X897559Y129408D03*
Y119408D03*
X922559Y129408D03*
Y119408D03*
X897559Y149408D03*
Y139408D03*
X922559Y149408D03*
Y139408D03*
X932559Y129408D03*
Y119408D03*
Y149408D03*
Y139408D03*
X1226024Y221929D03*
X1236024D03*
X1246024D03*
X1226024Y231929D03*
X1236024D03*
X1246024D03*
X1226024Y256929D03*
X1236024D03*
X1246024D03*
X1226024Y266929D03*
X1236024D03*
X1246024D03*
X1236024Y286929D03*
X1246024D03*
X1226024Y306929D03*
X1236024D03*
X1246024D03*
X1226024Y316929D03*
X1236024D03*
X1246024D03*
X1226024Y341929D03*
X1236024D03*
X1246024D03*
X1226024Y351929D03*
X1236024D03*
X1246024D03*
X1256024Y221929D03*
Y231929D03*
Y256929D03*
Y266929D03*
Y286929D03*
Y306929D03*
Y316929D03*
Y341929D03*
Y351929D03*
G54D68*
X832799Y337500D03*
X820201D03*
Y368600D03*
X832799D03*
Y360600D03*
X820201D03*
Y345500D03*
X832799D03*
G54D95*
X1226024Y174429D03*
Y399429D03*
G54D77*
X1025068Y151940D03*
Y173594D03*
X1052040Y151940D03*
Y173594D03*
G54D86*
X1124598Y166699D03*
G54D59*
X703740Y51237D03*
G54D96*
G01X0Y19685D02*
G03X19685Y0I19685J0D01*
G01X0Y63268D02*
Y19685D01*
G01X11811Y75079D02*
G03X0Y63268I0J-11811D01*
G01Y136102D02*
G03X11811Y124291I11811J0D01*
G01X0Y445787D02*
Y136102D01*
G01X11811Y457598D02*
G03X0Y445787I0J-11811D01*
G01Y518622D02*
G03X11811Y506811I11811J0D01*
G01X0Y559055D02*
Y518622D01*
G01X19685Y578740D02*
G03X0Y559055I0J-19685D01*
G01X19685Y0D02*
X1271654D01*
G01X37795Y75079D02*
X11811D01*
G01Y124291D02*
X37795D01*
G01Y457598D02*
X11811D01*
G01Y506811D02*
X37795D01*
G01X1271654Y578740D02*
X19685D01*
G01X39764Y122323D02*
Y77047D01*
G01D02*
G02X37795Y75079I-1969J1D01*
G01Y124291D02*
G02X39764Y122323I0J-1969D01*
G01Y504843D02*
Y459567D01*
G01D02*
G02X37795Y457598I-1969J0D01*
G01Y506811D02*
G02X39764Y504843I0J-1968D01*
G01X1271654Y0D02*
G03X1291339Y19685I0J19685D01*
G01Y559055D02*
G03X1271654Y578740I-19685J0D01*
G01X1291339Y19685D02*
Y559055D01*
G54D69*
X830630Y329000D03*
X834370D03*
G54D78*
X1041507Y149381D03*
X1039538D03*
X1037570D03*
X1035601D03*
Y176153D03*
X1037570D03*
X1039538D03*
X1041507D03*
X1047412Y149381D03*
X1045444D03*
X1043475D03*
Y176153D03*
X1045444D03*
X1047412D03*
G54D87*
X1116518Y159809D03*
Y157839D03*
Y155869D03*
Y177529D03*
Y175559D03*
Y173589D03*
Y171619D03*
Y169649D03*
Y167679D03*
Y165719D03*
Y163749D03*
Y161779D03*
X1147618Y155869D03*
Y157839D03*
Y159809D03*
Y161779D03*
Y163749D03*
Y165719D03*
Y167679D03*
Y169649D03*
Y171619D03*
Y173589D03*
Y175559D03*
Y177529D03*
G54D97*
G01X-297025Y-1013390D02*
Y1828909D01*
X3691357D01*
Y-1013390D01*
X-297025D01*
G01X4093Y-769672D02*
Y-844672D01*
X504093D01*
Y-769672D01*
X4093D01*
G01X16093Y-834672D02*
Y-839672D01*
G01X14636Y-834672D02*
X17550D01*
G01X22460Y-839672D02*
X19926D01*
Y-834672D01*
X22460D01*
G01X21446Y-837089D02*
X19926D01*
G01X25026Y-834672D02*
Y-839672D01*
X27560D01*
G01X31393Y-839839D02*
X31266Y-839755D01*
Y-839589D01*
X31393Y-839505D01*
X31520Y-839589D01*
Y-839755D01*
X31393Y-839839D01*
G01Y-837589D02*
X31266Y-837505D01*
Y-837339D01*
X31393Y-837255D01*
X31520Y-837339D01*
Y-837505D01*
X31393Y-837589D01*
G01X36176Y-841339D02*
X35543Y-840505D01*
X35226Y-839672D01*
Y-836339D01*
X35543Y-835505D01*
X36176Y-834672D01*
G01X41593D02*
X41086Y-834839D01*
X40706Y-835255D01*
X40453Y-835755D01*
X40263Y-836422D01*
X40200Y-837172D01*
X40263Y-837922D01*
X40453Y-838589D01*
X40706Y-839089D01*
X41086Y-839505D01*
X41593Y-839672D01*
X42100Y-839505D01*
X42480Y-839089D01*
X42733Y-838589D01*
X42923Y-837922D01*
X42986Y-837172D01*
X42923Y-836422D01*
X42733Y-835755D01*
X42480Y-835255D01*
X42100Y-834839D01*
X41593Y-834672D01*
G01X45300Y-838672D02*
X45680Y-839255D01*
X46186Y-839589D01*
X46756Y-839672D01*
X47263Y-839589D01*
X47770Y-839172D01*
X48086Y-838672D01*
X48150Y-838172D01*
X48023Y-837589D01*
X47580Y-837172D01*
X47136Y-837005D01*
X46566D01*
G01X47136D02*
X47516Y-836755D01*
X47833Y-836339D01*
X47960Y-835839D01*
X47833Y-835339D01*
X47516Y-834922D01*
X46946Y-834672D01*
X46376Y-834755D01*
X45806Y-835089D01*
G01X52110Y-841339D02*
X52743Y-840505D01*
X53060Y-839672D01*
Y-836339D01*
X52743Y-835505D01*
X52110Y-834672D01*
G01X55500Y-838672D02*
X55880Y-839255D01*
X56386Y-839589D01*
X56956Y-839672D01*
X57463Y-839589D01*
X57970Y-839172D01*
X58286Y-838672D01*
X58350Y-838172D01*
X58223Y-837589D01*
X57780Y-837172D01*
X57336Y-837005D01*
X56766D01*
G01X57336D02*
X57716Y-836755D01*
X58033Y-836339D01*
X58160Y-835839D01*
X58033Y-835339D01*
X57716Y-834922D01*
X57146Y-834672D01*
X56576Y-834755D01*
X56006Y-835089D01*
G01X60790Y-835505D02*
X61170Y-835005D01*
X61613Y-834755D01*
X62120Y-834672D01*
X62753Y-834839D01*
X63196Y-835255D01*
X63323Y-835755D01*
X63260Y-836255D01*
X63006Y-836672D01*
X61740Y-837505D01*
X61170Y-838089D01*
X60790Y-838922D01*
X60663Y-839672D01*
X63323D01*
G01X66966D02*
X67093Y-838589D01*
X67283Y-837672D01*
X67536Y-836839D01*
X67853Y-835922D01*
X68360Y-834672D01*
X65826D01*
G01X71370Y-838005D02*
X73016D01*
G01X76090Y-835505D02*
X76470Y-835005D01*
X76913Y-834755D01*
X77420Y-834672D01*
X78053Y-834839D01*
X78496Y-835255D01*
X78623Y-835755D01*
X78560Y-836255D01*
X78306Y-836672D01*
X77040Y-837505D01*
X76470Y-838089D01*
X76090Y-838922D01*
X75963Y-839672D01*
X78623D01*
G01X81000Y-838672D02*
X81380Y-839255D01*
X81886Y-839589D01*
X82456Y-839672D01*
X82963Y-839589D01*
X83470Y-839172D01*
X83786Y-838672D01*
X83850Y-838172D01*
X83723Y-837589D01*
X83280Y-837172D01*
X82836Y-837005D01*
X82266D01*
G01X82836D02*
X83216Y-836755D01*
X83533Y-836339D01*
X83660Y-835839D01*
X83533Y-835339D01*
X83216Y-834922D01*
X82646Y-834672D01*
X82076Y-834755D01*
X81506Y-835089D01*
G01X88253Y-839672D02*
Y-834672D01*
X85910Y-838255D01*
X89076D01*
G01X91200Y-838922D02*
X91580Y-839339D01*
X92023Y-839589D01*
X92593Y-839672D01*
X93163Y-839505D01*
X93606Y-839172D01*
X93923Y-838589D01*
X93986Y-837922D01*
X93860Y-837255D01*
X93543Y-836839D01*
X93100Y-836505D01*
X92656Y-836422D01*
X92213Y-836505D01*
X91643Y-836839D01*
X91833Y-834672D01*
X93543D01*
G01X101590Y-839672D02*
Y-834672D01*
X103996D01*
G01X103110Y-837089D02*
X101590D01*
G01X106310Y-839672D02*
X107893Y-834672D01*
X109476Y-839672D01*
G01X108906Y-837922D02*
X106880D01*
G01X111663Y-839672D02*
X114323Y-834672D01*
G01X111663D02*
X114323Y-839672D01*
G01X118093Y-839839D02*
X117966Y-839755D01*
Y-839589D01*
X118093Y-839505D01*
X118220Y-839589D01*
Y-839755D01*
X118093Y-839839D01*
G01Y-837589D02*
X117966Y-837505D01*
Y-837339D01*
X118093Y-837255D01*
X118220Y-837339D01*
Y-837505D01*
X118093Y-837589D01*
G01X122876Y-841339D02*
X122243Y-840505D01*
X121926Y-839672D01*
Y-836339D01*
X122243Y-835505D01*
X122876Y-834672D01*
G01X128293D02*
X127786Y-834839D01*
X127406Y-835255D01*
X127153Y-835755D01*
X126963Y-836422D01*
X126900Y-837172D01*
X126963Y-837922D01*
X127153Y-838589D01*
X127406Y-839089D01*
X127786Y-839505D01*
X128293Y-839672D01*
X128800Y-839505D01*
X129180Y-839089D01*
X129433Y-838589D01*
X129623Y-837922D01*
X129686Y-837172D01*
X129623Y-836422D01*
X129433Y-835755D01*
X129180Y-835255D01*
X128800Y-834839D01*
X128293Y-834672D01*
G01X132000Y-838672D02*
X132380Y-839255D01*
X132886Y-839589D01*
X133456Y-839672D01*
X133963Y-839589D01*
X134470Y-839172D01*
X134786Y-838672D01*
X134850Y-838172D01*
X134723Y-837589D01*
X134280Y-837172D01*
X133836Y-837005D01*
X133266D01*
G01X133836D02*
X134216Y-836755D01*
X134533Y-836339D01*
X134660Y-835839D01*
X134533Y-835339D01*
X134216Y-834922D01*
X133646Y-834672D01*
X133076Y-834755D01*
X132506Y-835089D01*
G01X138810Y-841339D02*
X139443Y-840505D01*
X139760Y-839672D01*
Y-836339D01*
X139443Y-835505D01*
X138810Y-834672D01*
G01X142200Y-838672D02*
X142580Y-839255D01*
X143086Y-839589D01*
X143656Y-839672D01*
X144163Y-839589D01*
X144670Y-839172D01*
X144986Y-838672D01*
X145050Y-838172D01*
X144923Y-837589D01*
X144480Y-837172D01*
X144036Y-837005D01*
X143466D01*
G01X144036D02*
X144416Y-836755D01*
X144733Y-836339D01*
X144860Y-835839D01*
X144733Y-835339D01*
X144416Y-834922D01*
X143846Y-834672D01*
X143276Y-834755D01*
X142706Y-835089D01*
G01X147616Y-839089D02*
X148060Y-839505D01*
X148566Y-839672D01*
X149073Y-839505D01*
X149516Y-839005D01*
X149833Y-838255D01*
X149960Y-837505D01*
Y-836589D01*
X149833Y-835839D01*
X149516Y-835172D01*
X149136Y-834839D01*
X148693Y-834672D01*
X148186Y-834839D01*
X147806Y-835172D01*
X147553Y-835672D01*
X147426Y-836339D01*
X147553Y-836922D01*
X147870Y-837505D01*
X148250Y-837839D01*
X148693Y-837922D01*
X149200Y-837755D01*
X149580Y-837339D01*
X149960Y-836589D01*
G01X153666Y-839672D02*
X153793Y-838589D01*
X153983Y-837672D01*
X154236Y-836839D01*
X154553Y-835922D01*
X155060Y-834672D01*
X152526D01*
G01X158070Y-838005D02*
X159716D01*
G01X162600Y-838672D02*
X162980Y-839255D01*
X163486Y-839589D01*
X164056Y-839672D01*
X164563Y-839589D01*
X165070Y-839172D01*
X165386Y-838672D01*
X165450Y-838172D01*
X165323Y-837589D01*
X164880Y-837172D01*
X164436Y-837005D01*
X163866D01*
G01X164436D02*
X164816Y-836755D01*
X165133Y-836339D01*
X165260Y-835839D01*
X165133Y-835339D01*
X164816Y-834922D01*
X164246Y-834672D01*
X163676Y-834755D01*
X163106Y-835089D01*
G01X167890Y-837589D02*
X168333Y-837005D01*
X168713Y-836672D01*
X169220Y-836505D01*
X169663Y-836672D01*
X169980Y-837005D01*
X170233Y-837505D01*
X170296Y-838089D01*
X170233Y-838589D01*
X169980Y-839089D01*
X169600Y-839505D01*
X169156Y-839672D01*
X168650Y-839505D01*
X168206Y-839005D01*
X167953Y-838255D01*
X167890Y-837422D01*
X168016Y-836339D01*
X168206Y-835755D01*
X168523Y-835172D01*
X168966Y-834755D01*
X169410Y-834672D01*
X169853Y-834839D01*
X170170Y-835255D01*
G01X174193Y-839672D02*
Y-834672D01*
X173433Y-835672D01*
G01Y-839672D02*
X174953D01*
G01X180053D02*
Y-834672D01*
X177710Y-838255D01*
X180876D01*
G01X199093Y-769672D02*
Y-844672D01*
G01Y-819672D02*
X302093D01*
Y-794672D01*
G01X199093D02*
X302093D01*
G01X309600Y-829672D02*
Y-824672D01*
X310866D01*
X311373Y-824922D01*
X311753Y-825255D01*
X312070Y-825755D01*
X312323Y-826339D01*
X312386Y-827172D01*
X312323Y-828005D01*
X312070Y-828589D01*
X311753Y-829089D01*
X311373Y-829422D01*
X310866Y-829672D01*
X309600D01*
G01X314510D02*
X316093Y-824672D01*
X317676Y-829672D01*
G01X317106Y-827922D02*
X315080D01*
G01X321193Y-824672D02*
Y-829672D01*
G01X319736Y-824672D02*
X322650D01*
G01X327560Y-829672D02*
X325026D01*
Y-824672D01*
X327560D01*
G01X326546Y-827089D02*
X325026D01*
G01X331393Y-829839D02*
X331266Y-829755D01*
Y-829589D01*
X331393Y-829505D01*
X331520Y-829589D01*
Y-829755D01*
X331393Y-829839D01*
G01Y-827589D02*
X331266Y-827505D01*
Y-827339D01*
X331393Y-827255D01*
X331520Y-827339D01*
Y-827505D01*
X331393Y-827589D01*
G01X304093Y-769672D02*
Y-844672D01*
G01X302093Y-769672D02*
Y-844672D01*
G01X304093Y-819672D02*
X504093D01*
G01X309726Y-804672D02*
Y-799672D01*
X311246D01*
X311753Y-799922D01*
X312133Y-800505D01*
X312260Y-801172D01*
X312133Y-801839D01*
X311816Y-802339D01*
X311246Y-802589D01*
X309726D01*
G01X314953Y-804839D02*
X317233Y-799672D01*
G01X319736Y-804672D02*
Y-799672D01*
X322650Y-804672D01*
Y-799672D01*
G01X326293Y-804839D02*
X326166Y-804755D01*
Y-804589D01*
X326293Y-804505D01*
X326420Y-804589D01*
Y-804755D01*
X326293Y-804839D01*
G01Y-802589D02*
X326166Y-802505D01*
Y-802339D01*
X326293Y-802255D01*
X326420Y-802339D01*
Y-802505D01*
X326293Y-802589D01*
G01X304093Y-794672D02*
X504093D01*
G01X309726Y-779672D02*
Y-774672D01*
X311246D01*
X311753Y-774922D01*
X312133Y-775505D01*
X312260Y-776172D01*
X312133Y-776839D01*
X311816Y-777339D01*
X311246Y-777589D01*
X309726D01*
G01X314826Y-779672D02*
Y-774672D01*
X316410D01*
X316916Y-774922D01*
X317233Y-775255D01*
X317360Y-775922D01*
X317233Y-776589D01*
X316853Y-777005D01*
X316410Y-777255D01*
X314826D01*
G01X316410D02*
X317360Y-779672D01*
G01X321193D02*
X320686Y-779589D01*
X320243Y-779255D01*
X319863Y-778755D01*
X319610Y-778172D01*
X319483Y-777505D01*
Y-776839D01*
X319610Y-776172D01*
X319863Y-775589D01*
X320243Y-775089D01*
X320686Y-774755D01*
X321193Y-774672D01*
X321700Y-774755D01*
X322143Y-775089D01*
X322523Y-775589D01*
X322776Y-776172D01*
X322903Y-776839D01*
Y-777505D01*
X322776Y-778172D01*
X322523Y-778755D01*
X322143Y-779255D01*
X321700Y-779589D01*
X321193Y-779672D01*
G01X325026Y-778672D02*
X325343Y-779172D01*
X325723Y-779505D01*
X326166Y-779672D01*
X326673Y-779505D01*
X327053Y-779172D01*
X327433Y-778672D01*
X327560Y-778005D01*
Y-774672D01*
G01X332660Y-779672D02*
X330126D01*
Y-774672D01*
X332660D01*
G01X331646Y-777089D02*
X330126D01*
G01X337886Y-775089D02*
X337506Y-774839D01*
X337063Y-774672D01*
X336556D01*
X335986Y-774922D01*
X335543Y-775339D01*
X335226Y-775839D01*
X334973Y-776672D01*
X334910Y-777422D01*
X335036Y-778172D01*
X335226Y-778672D01*
X335606Y-779172D01*
X336050Y-779505D01*
X336493Y-779672D01*
X336936D01*
X337380Y-779505D01*
X337760Y-779255D01*
X338076Y-778922D01*
G01X341593Y-774672D02*
Y-779672D01*
G01X340136Y-774672D02*
X343050D01*
G01X346693Y-779839D02*
X346566Y-779755D01*
Y-779589D01*
X346693Y-779505D01*
X346820Y-779589D01*
Y-779755D01*
X346693Y-779839D01*
G01Y-777589D02*
X346566Y-777505D01*
Y-777339D01*
X346693Y-777255D01*
X346820Y-777339D01*
Y-777505D01*
X346693Y-777589D01*
G01X419093Y-819672D02*
Y-844672D01*
G01X421726Y-822172D02*
Y-827172D01*
X424260D01*
G01X427333Y-822172D02*
X428853D01*
G01X428093D02*
Y-827172D01*
G01X427333D02*
X428853D01*
G01X433700Y-824505D02*
X433953Y-824255D01*
X434143Y-823839D01*
X434270Y-823255D01*
X434143Y-822755D01*
X433890Y-822422D01*
X433446Y-822172D01*
X431736D01*
Y-827172D01*
X433826D01*
X434270Y-826839D01*
X434523Y-826339D01*
X434650Y-825755D01*
X434523Y-825172D01*
X434143Y-824672D01*
X433700Y-824505D01*
X431736D01*
G01X438293Y-827339D02*
X438166Y-827255D01*
Y-827089D01*
X438293Y-827005D01*
X438420Y-827089D01*
Y-827255D01*
X438293Y-827339D01*
G01Y-825089D02*
X438166Y-825005D01*
Y-824839D01*
X438293Y-824755D01*
X438420Y-824839D01*
Y-825005D01*
X438293Y-825089D01*
G01X470106Y-847839D02*
X470213Y-847714D01*
X470293Y-847505D01*
X470346Y-847214D01*
X470293Y-846964D01*
X470186Y-846797D01*
X470000Y-846672D01*
X469280D01*
Y-849172D01*
X470160D01*
X470346Y-849005D01*
X470453Y-848755D01*
X470506Y-848464D01*
X470453Y-848172D01*
X470293Y-847922D01*
X470106Y-847839D01*
X469280D01*
G01X472573Y-849172D02*
Y-847505D01*
G01Y-847797D02*
X472466Y-847630D01*
X472306Y-847547D01*
X472120Y-847505D01*
X471933Y-847589D01*
X471773Y-847755D01*
X471666Y-848005D01*
X471613Y-848339D01*
X471666Y-848672D01*
X471773Y-848922D01*
X471933Y-849089D01*
X472120Y-849172D01*
X472306Y-849130D01*
X472466Y-849005D01*
X472573Y-848839D01*
G01X473893Y-848880D02*
X474026Y-849047D01*
X474213Y-849172D01*
X474373D01*
X474533Y-849089D01*
X474640Y-848964D01*
X474693Y-848797D01*
X474666Y-848547D01*
X474560Y-848422D01*
X474080Y-848172D01*
X473973Y-847880D01*
X474026Y-847672D01*
X474133Y-847547D01*
X474293Y-847505D01*
X474453Y-847547D01*
X474613Y-847672D01*
G01X476093Y-848047D02*
X476946D01*
X476866Y-847755D01*
X476733Y-847589D01*
X476546Y-847505D01*
X476360Y-847547D01*
X476200Y-847672D01*
X476093Y-847964D01*
X476040Y-848214D01*
Y-848464D01*
X476093Y-848714D01*
X476226Y-848964D01*
X476386Y-849130D01*
X476573Y-849172D01*
X476760Y-849089D01*
X476946Y-848839D01*
G01X478213Y-849172D02*
Y-846672D01*
G01Y-847922D02*
X478346Y-847672D01*
X478506Y-847547D01*
X478666Y-847505D01*
X478906Y-847589D01*
X479066Y-847755D01*
X479173Y-848047D01*
Y-848380D01*
X479120Y-848714D01*
X479013Y-848964D01*
X478826Y-849130D01*
X478666Y-849172D01*
X478506Y-849130D01*
X478346Y-849005D01*
X478213Y-848797D01*
G01X480893Y-849172D02*
X480733Y-849130D01*
X480573Y-848964D01*
X480466Y-848672D01*
X480413Y-848339D01*
X480466Y-848005D01*
X480573Y-847714D01*
X480733Y-847547D01*
X480893Y-847505D01*
X481053Y-847547D01*
X481213Y-847714D01*
X481320Y-848005D01*
X481346Y-848339D01*
X481320Y-848672D01*
X481213Y-848964D01*
X481053Y-849130D01*
X480893Y-849172D01*
G01X483573D02*
Y-847505D01*
G01Y-847797D02*
X483466Y-847630D01*
X483306Y-847547D01*
X483120Y-847505D01*
X482933Y-847589D01*
X482773Y-847755D01*
X482666Y-848005D01*
X482613Y-848339D01*
X482666Y-848672D01*
X482773Y-848922D01*
X482933Y-849089D01*
X483120Y-849172D01*
X483306Y-849130D01*
X483466Y-849005D01*
X483573Y-848839D01*
G01X484920Y-849172D02*
Y-847505D01*
G01Y-847839D02*
X485053Y-847672D01*
X485186Y-847547D01*
X485373Y-847505D01*
X485506Y-847547D01*
X485666Y-847672D01*
G01X487973Y-846672D02*
Y-849172D01*
G01Y-848797D02*
X487866Y-849005D01*
X487706Y-849130D01*
X487520Y-849172D01*
X487306Y-849089D01*
X487146Y-848880D01*
X487040Y-848630D01*
X487013Y-848339D01*
X487040Y-848047D01*
X487146Y-847797D01*
X487306Y-847589D01*
X487520Y-847505D01*
X487706Y-847547D01*
X487840Y-847630D01*
X487973Y-847797D01*
G01X491360Y-849172D02*
Y-846672D01*
X492026D01*
X492240Y-846797D01*
X492373Y-846964D01*
X492426Y-847297D01*
X492373Y-847630D01*
X492213Y-847839D01*
X492026Y-847964D01*
X491360D01*
G01X492026D02*
X492426Y-849172D01*
G01X493693Y-848047D02*
X494546D01*
X494466Y-847755D01*
X494333Y-847589D01*
X494146Y-847505D01*
X493960Y-847547D01*
X493800Y-847672D01*
X493693Y-847964D01*
X493640Y-848214D01*
Y-848464D01*
X493693Y-848714D01*
X493826Y-848964D01*
X493986Y-849130D01*
X494173Y-849172D01*
X494360Y-849089D01*
X494546Y-848839D01*
G01X495813Y-847505D02*
X496293Y-849172D01*
X496773Y-847505D01*
G01X498493Y-849255D02*
X498440Y-849214D01*
Y-849130D01*
X498493Y-849089D01*
X498546Y-849130D01*
Y-849214D01*
X498493Y-849255D01*
G01X500693Y-849172D02*
X500880Y-849130D01*
X501093Y-849005D01*
X501226Y-848797D01*
X501280Y-848505D01*
X501226Y-848214D01*
X501066Y-847964D01*
X500826Y-847839D01*
X500560D01*
X500400Y-847755D01*
X500266Y-847547D01*
X500213Y-847255D01*
X500293Y-846964D01*
X500480Y-846755D01*
X500693Y-846672D01*
X500906Y-846755D01*
X501093Y-846964D01*
X501173Y-847255D01*
X501120Y-847547D01*
X500986Y-847755D01*
X500826Y-847839D01*
X500560D01*
X500320Y-847964D01*
X500160Y-848214D01*
X500106Y-848505D01*
X500160Y-848797D01*
X500293Y-849005D01*
X500506Y-849130D01*
X500693Y-849172D01*
G01X503106Y-847839D02*
X503213Y-847714D01*
X503293Y-847505D01*
X503346Y-847214D01*
X503293Y-846964D01*
X503186Y-846797D01*
X503000Y-846672D01*
X502280D01*
Y-849172D01*
X503160D01*
X503346Y-849005D01*
X503453Y-848755D01*
X503506Y-848464D01*
X503453Y-848172D01*
X503293Y-847922D01*
X503106Y-847839D01*
X502280D01*
G01X465993Y-822172D02*
Y-827172D01*
G01X464536Y-822172D02*
X467450D01*
G01X471093Y-827172D02*
X470713Y-827089D01*
X470333Y-826755D01*
X470080Y-826172D01*
X469953Y-825505D01*
X470080Y-824839D01*
X470333Y-824255D01*
X470713Y-823922D01*
X471093Y-823839D01*
X471473Y-823922D01*
X471853Y-824255D01*
X472106Y-824839D01*
X472170Y-825505D01*
X472106Y-826172D01*
X471853Y-826755D01*
X471473Y-827089D01*
X471093Y-827172D01*
G01X476193D02*
X475813Y-827089D01*
X475433Y-826755D01*
X475180Y-826172D01*
X475053Y-825505D01*
X475180Y-824839D01*
X475433Y-824255D01*
X475813Y-823922D01*
X476193Y-823839D01*
X476573Y-823922D01*
X476953Y-824255D01*
X477206Y-824839D01*
X477270Y-825505D01*
X477206Y-826172D01*
X476953Y-826755D01*
X476573Y-827089D01*
X476193Y-827172D01*
G01X481293D02*
Y-822172D01*
G01X486393Y-827339D02*
X486266Y-827255D01*
Y-827089D01*
X486393Y-827005D01*
X486520Y-827089D01*
Y-827255D01*
X486393Y-827339D01*
G01Y-825089D02*
X486266Y-825005D01*
Y-824839D01*
X486393Y-824755D01*
X486520Y-824839D01*
Y-825005D01*
X486393Y-825089D01*
G01X462093Y-819672D02*
Y-844672D01*
G01Y-794672D02*
Y-819672D01*
G01X464726Y-802172D02*
Y-797172D01*
X466310D01*
X466816Y-797422D01*
X467133Y-797755D01*
X467260Y-798422D01*
X467133Y-799089D01*
X466753Y-799505D01*
X466310Y-799755D01*
X464726D01*
G01X466310D02*
X467260Y-802172D01*
G01X472360D02*
X469826D01*
Y-797172D01*
X472360D01*
G01X471346Y-799589D02*
X469826D01*
G01X474610Y-797172D02*
X476193Y-802172D01*
X477776Y-797172D01*
G01X481293Y-802339D02*
X481166Y-802255D01*
Y-802089D01*
X481293Y-802005D01*
X481420Y-802089D01*
Y-802255D01*
X481293Y-802339D01*
G01Y-800089D02*
X481166Y-800005D01*
Y-799839D01*
X481293Y-799755D01*
X481420Y-799839D01*
Y-800005D01*
X481293Y-800089D01*
G01X-297025Y-1013390D02*
Y1828909D01*
X3691357D01*
Y-1013390D01*
X-297025D01*
G01X16913Y-817022D02*
X18480D01*
Y-818912D01*
X18010Y-819542D01*
X17461Y-819962D01*
X16678Y-820172D01*
X15895Y-819962D01*
X15346Y-819542D01*
X14876Y-818912D01*
X14563Y-818177D01*
X14406Y-817337D01*
Y-816602D01*
X14563Y-815972D01*
X14876Y-815237D01*
X15346Y-814607D01*
X15816Y-814187D01*
X16443Y-813872D01*
X16991D01*
X17618Y-814082D01*
X18088Y-814502D01*
G01X21020Y-813872D02*
Y-818387D01*
X21333Y-819332D01*
X21960Y-819962D01*
X22743Y-820172D01*
X23526Y-819962D01*
X24153Y-819332D01*
X24466Y-818387D01*
Y-813872D01*
G01X28103D02*
X29983D01*
G01X29043D02*
Y-820172D01*
G01X28103D02*
X29983D01*
G01X33698Y-819332D02*
X34325Y-819857D01*
X35030Y-820172D01*
X35656D01*
X36283Y-819857D01*
X36753Y-819332D01*
X36988Y-818597D01*
X36831Y-817862D01*
X36440Y-817232D01*
X35735Y-816812D01*
X34795Y-816602D01*
X34246Y-816182D01*
X34011Y-815447D01*
X34168Y-814712D01*
X34560Y-814187D01*
X35108Y-813872D01*
X35656D01*
X36205Y-814082D01*
X36675Y-814607D01*
G01X39998Y-820172D02*
Y-813872D01*
G01X43288D02*
Y-820172D01*
G01Y-817022D02*
X39998D01*
G01X45985Y-820172D02*
X47943Y-813872D01*
X49901Y-820172D01*
G01X49196Y-817967D02*
X46690D01*
G01X52441Y-820172D02*
Y-813872D01*
X56045Y-820172D01*
Y-813872D01*
G01X65120Y-820172D02*
Y-813872D01*
X66686D01*
X67313Y-814187D01*
X67783Y-814607D01*
X68175Y-815237D01*
X68488Y-815972D01*
X68566Y-817022D01*
X68488Y-818072D01*
X68175Y-818807D01*
X67783Y-819437D01*
X67313Y-819857D01*
X66686Y-820172D01*
X65120D01*
G01X72203Y-813872D02*
X74083D01*
G01X73143D02*
Y-820172D01*
G01X72203D02*
X74083D01*
G01X77798Y-819332D02*
X78425Y-819857D01*
X79130Y-820172D01*
X79756D01*
X80383Y-819857D01*
X80853Y-819332D01*
X81088Y-818597D01*
X80931Y-817862D01*
X80540Y-817232D01*
X79835Y-816812D01*
X78895Y-816602D01*
X78346Y-816182D01*
X78111Y-815447D01*
X78268Y-814712D01*
X78660Y-814187D01*
X79208Y-813872D01*
X79756D01*
X80305Y-814082D01*
X80775Y-814607D01*
G01X85743Y-813872D02*
Y-820172D01*
G01X83941Y-813872D02*
X87545D01*
G01X92043Y-820382D02*
X91886Y-820277D01*
Y-820067D01*
X92043Y-819962D01*
X92200Y-820067D01*
Y-820277D01*
X92043Y-820382D01*
G01X98186Y-821327D02*
X98500Y-819962D01*
G01X104643Y-813872D02*
Y-820172D01*
G01X102841Y-813872D02*
X106445D01*
G01X108985Y-820172D02*
X110943Y-813872D01*
X112901Y-820172D01*
G01X112196Y-817967D02*
X109690D01*
G01X117243Y-820172D02*
X116616Y-820067D01*
X116068Y-819647D01*
X115598Y-819017D01*
X115285Y-818282D01*
X115128Y-817442D01*
Y-816602D01*
X115285Y-815762D01*
X115598Y-815027D01*
X116068Y-814397D01*
X116616Y-813977D01*
X117243Y-813872D01*
X117870Y-813977D01*
X118418Y-814397D01*
X118888Y-815027D01*
X119201Y-815762D01*
X119358Y-816602D01*
Y-817442D01*
X119201Y-818282D01*
X118888Y-819017D01*
X118418Y-819647D01*
X117870Y-820067D01*
X117243Y-820172D01*
G01X123543D02*
Y-817337D01*
X121976Y-813872D01*
G01X125110D02*
X123543Y-817337D01*
G01X128120Y-813872D02*
Y-818387D01*
X128433Y-819332D01*
X129060Y-819962D01*
X129843Y-820172D01*
X130626Y-819962D01*
X131253Y-819332D01*
X131566Y-818387D01*
Y-813872D01*
G01X134185Y-820172D02*
X136143Y-813872D01*
X138101Y-820172D01*
G01X137396Y-817967D02*
X134890D01*
G01X140641Y-820172D02*
Y-813872D01*
X144245Y-820172D01*
Y-813872D01*
G01X18166Y-824397D02*
X17696Y-824082D01*
X17148Y-823872D01*
X16521D01*
X15816Y-824187D01*
X15268Y-824712D01*
X14876Y-825342D01*
X14563Y-826392D01*
X14485Y-827337D01*
X14641Y-828282D01*
X14876Y-828912D01*
X15346Y-829542D01*
X15895Y-829962D01*
X16443Y-830172D01*
X16991D01*
X17540Y-829962D01*
X18010Y-829647D01*
X18401Y-829227D01*
G01X21803Y-823872D02*
X23683D01*
G01X22743D02*
Y-830172D01*
G01X21803D02*
X23683D01*
G01X29043Y-823872D02*
Y-830172D01*
G01X27241Y-823872D02*
X30845D01*
G01X35343Y-830172D02*
Y-827337D01*
X33776Y-823872D01*
G01X36910D02*
X35343Y-827337D01*
G01X46220Y-828912D02*
X46690Y-829647D01*
X47316Y-830067D01*
X48021Y-830172D01*
X48648Y-830067D01*
X49275Y-829542D01*
X49666Y-828912D01*
X49745Y-828282D01*
X49588Y-827547D01*
X49040Y-827022D01*
X48491Y-826812D01*
X47786D01*
G01X48491D02*
X48961Y-826497D01*
X49353Y-825972D01*
X49510Y-825342D01*
X49353Y-824712D01*
X48961Y-824187D01*
X48256Y-823872D01*
X47551Y-823977D01*
X46846Y-824397D01*
G01X52520Y-828912D02*
X52990Y-829647D01*
X53616Y-830067D01*
X54321Y-830172D01*
X54948Y-830067D01*
X55575Y-829542D01*
X55966Y-828912D01*
X56045Y-828282D01*
X55888Y-827547D01*
X55340Y-827022D01*
X54791Y-826812D01*
X54086D01*
G01X54791D02*
X55261Y-826497D01*
X55653Y-825972D01*
X55810Y-825342D01*
X55653Y-824712D01*
X55261Y-824187D01*
X54556Y-823872D01*
X53851Y-823977D01*
X53146Y-824397D01*
G01X58820Y-828912D02*
X59290Y-829647D01*
X59916Y-830067D01*
X60621Y-830172D01*
X61248Y-830067D01*
X61875Y-829542D01*
X62266Y-828912D01*
X62345Y-828282D01*
X62188Y-827547D01*
X61640Y-827022D01*
X61091Y-826812D01*
X60386D01*
G01X61091D02*
X61561Y-826497D01*
X61953Y-825972D01*
X62110Y-825342D01*
X61953Y-824712D01*
X61561Y-824187D01*
X60856Y-823872D01*
X60151Y-823977D01*
X59446Y-824397D01*
G01X66686Y-830172D02*
X66843Y-828807D01*
X67078Y-827652D01*
X67391Y-826602D01*
X67783Y-825447D01*
X68410Y-823872D01*
X65276D01*
G01X72986Y-830172D02*
X73143Y-828807D01*
X73378Y-827652D01*
X73691Y-826602D01*
X74083Y-825447D01*
X74710Y-823872D01*
X71576D01*
G01X79286Y-831327D02*
X79600Y-829962D01*
G01X85743Y-823872D02*
Y-830172D01*
G01X83941Y-823872D02*
X87545D01*
G01X90085Y-830172D02*
X92043Y-823872D01*
X94001Y-830172D01*
G01X93296Y-827967D02*
X90790D01*
G01X97403Y-823872D02*
X99283D01*
G01X98343D02*
Y-830172D01*
G01X97403D02*
X99283D01*
G01X102293Y-823872D02*
X103390Y-830172D01*
X104643Y-823872D01*
X105896Y-830172D01*
X106993Y-823872D01*
G01X108985Y-830172D02*
X110943Y-823872D01*
X112901Y-830172D01*
G01X112196Y-827967D02*
X109690D01*
G01X115441Y-830172D02*
Y-823872D01*
X119045Y-830172D01*
Y-823872D01*
G01X129451Y-832272D02*
X128668Y-831222D01*
X128276Y-830172D01*
Y-825972D01*
X128668Y-824922D01*
X129451Y-823872D01*
G01X140876Y-830172D02*
Y-823872D01*
X142835D01*
X143461Y-824187D01*
X143853Y-824607D01*
X144010Y-825447D01*
X143853Y-826287D01*
X143383Y-826812D01*
X142835Y-827127D01*
X140876D01*
G01X142835D02*
X144010Y-830172D01*
G01X148743Y-830382D02*
X148586Y-830277D01*
Y-830067D01*
X148743Y-829962D01*
X148900Y-830067D01*
Y-830277D01*
X148743Y-830382D01*
G01X155043Y-830172D02*
X154416Y-830067D01*
X153868Y-829647D01*
X153398Y-829017D01*
X153085Y-828282D01*
X152928Y-827442D01*
Y-826602D01*
X153085Y-825762D01*
X153398Y-825027D01*
X153868Y-824397D01*
X154416Y-823977D01*
X155043Y-823872D01*
X155670Y-823977D01*
X156218Y-824397D01*
X156688Y-825027D01*
X157001Y-825762D01*
X157158Y-826602D01*
Y-827442D01*
X157001Y-828282D01*
X156688Y-829017D01*
X156218Y-829647D01*
X155670Y-830067D01*
X155043Y-830172D01*
G01X161343Y-830382D02*
X161186Y-830277D01*
Y-830067D01*
X161343Y-829962D01*
X161500Y-830067D01*
Y-830277D01*
X161343Y-830382D01*
G01X169366Y-824397D02*
X168896Y-824082D01*
X168348Y-823872D01*
X167721D01*
X167016Y-824187D01*
X166468Y-824712D01*
X166076Y-825342D01*
X165763Y-826392D01*
X165685Y-827337D01*
X165841Y-828282D01*
X166076Y-828912D01*
X166546Y-829542D01*
X167095Y-829962D01*
X167643Y-830172D01*
X168191D01*
X168740Y-829962D01*
X169210Y-829647D01*
X169601Y-829227D01*
G01X173943Y-830382D02*
X173786Y-830277D01*
Y-830067D01*
X173943Y-829962D01*
X174100Y-830067D01*
Y-830277D01*
X173943Y-830382D01*
G01X180635Y-832272D02*
X181418Y-831222D01*
X181810Y-830172D01*
Y-825972D01*
X181418Y-824922D01*
X180635Y-823872D01*
G01X38743Y-799472D02*
X36223Y-799055D01*
X34018Y-797389D01*
X32128Y-794889D01*
X30868Y-791972D01*
X30238Y-788639D01*
Y-785305D01*
X30868Y-781972D01*
X32128Y-779055D01*
X34018Y-776556D01*
X36223Y-774889D01*
X38743Y-774472D01*
X41263Y-774889D01*
X43468Y-776556D01*
X45358Y-779055D01*
X46618Y-781972D01*
X47248Y-785305D01*
Y-788639D01*
X46618Y-791972D01*
X45358Y-794889D01*
X43468Y-797389D01*
X41263Y-799055D01*
X38743Y-799472D01*
G01X41263Y-792805D02*
X45043Y-799472D01*
G01X58588Y-782806D02*
Y-794472D01*
X59848Y-797389D01*
X61738Y-799055D01*
X63943Y-799472D01*
X66148Y-799055D01*
X68038Y-797389D01*
X69298Y-794472D01*
G01Y-799472D02*
Y-782806D01*
G01X94813Y-799472D02*
Y-782806D01*
G01Y-785722D02*
X93553Y-784056D01*
X91663Y-783222D01*
X89458Y-782806D01*
X87253Y-783639D01*
X85363Y-785305D01*
X84103Y-787806D01*
X83473Y-791139D01*
X84103Y-794472D01*
X85363Y-796973D01*
X87253Y-798639D01*
X89458Y-799472D01*
X91663Y-799055D01*
X93553Y-797806D01*
X94813Y-796139D01*
G01X108988Y-799472D02*
Y-782806D01*
G01Y-786972D02*
X110248Y-784889D01*
X112138Y-783222D01*
X114658Y-782806D01*
X116863Y-783222D01*
X118753Y-784889D01*
X119698Y-787806D01*
Y-799472D01*
G01X139543Y-774472D02*
Y-799472D01*
G01X135133Y-782806D02*
X143953D01*
G01X170413Y-799472D02*
Y-782806D01*
G01Y-785722D02*
X169153Y-784056D01*
X167263Y-783222D01*
X165058Y-782806D01*
X162853Y-783639D01*
X160963Y-785305D01*
X159703Y-787806D01*
X159073Y-791139D01*
X159703Y-794472D01*
X160963Y-796973D01*
X162853Y-798639D01*
X165058Y-799472D01*
X167263Y-799055D01*
X169153Y-797806D01*
X170413Y-796139D01*
G01X14641Y-810172D02*
Y-803872D01*
X18245Y-810172D01*
Y-803872D01*
G01X22743Y-810172D02*
X22116Y-810067D01*
X21568Y-809647D01*
X21098Y-809017D01*
X20785Y-808282D01*
X20628Y-807442D01*
Y-806602D01*
X20785Y-805762D01*
X21098Y-805027D01*
X21568Y-804397D01*
X22116Y-803977D01*
X22743Y-803872D01*
X23370Y-803977D01*
X23918Y-804397D01*
X24388Y-805027D01*
X24701Y-805762D01*
X24858Y-806602D01*
Y-807442D01*
X24701Y-808282D01*
X24388Y-809017D01*
X23918Y-809647D01*
X23370Y-810067D01*
X22743Y-810172D01*
G01X29043Y-810382D02*
X28886Y-810277D01*
Y-810067D01*
X29043Y-809962D01*
X29200Y-810067D01*
Y-810277D01*
X29043Y-810382D01*
G01X33855Y-804922D02*
X34325Y-804292D01*
X34873Y-803977D01*
X35500Y-803872D01*
X36283Y-804082D01*
X36831Y-804607D01*
X36988Y-805237D01*
X36910Y-805867D01*
X36596Y-806392D01*
X35030Y-807442D01*
X34325Y-808177D01*
X33855Y-809227D01*
X33698Y-810172D01*
X36988D01*
G01X41643D02*
Y-803872D01*
X40703Y-805132D01*
G01Y-810172D02*
X42583D01*
G01X47943D02*
Y-803872D01*
X47003Y-805132D01*
G01Y-810172D02*
X48883D01*
G01X54086Y-811327D02*
X54400Y-809962D01*
G01X58193Y-803872D02*
X59290Y-810172D01*
X60543Y-803872D01*
X61796Y-810172D01*
X62893Y-803872D01*
G01X68410Y-810172D02*
X65276D01*
Y-803872D01*
X68410D01*
G01X67156Y-806917D02*
X65276D01*
G01X71341Y-810172D02*
Y-803872D01*
X74945Y-810172D01*
Y-803872D01*
G01X77798Y-810172D02*
Y-803872D01*
G01X81088D02*
Y-810172D01*
G01Y-807022D02*
X77798D01*
G01X84020Y-803872D02*
Y-808387D01*
X84333Y-809332D01*
X84960Y-809962D01*
X85743Y-810172D01*
X86526Y-809962D01*
X87153Y-809332D01*
X87466Y-808387D01*
Y-803872D01*
G01X90085Y-810172D02*
X92043Y-803872D01*
X94001Y-810172D01*
G01X93296Y-807967D02*
X90790D01*
G01X103155Y-804922D02*
X103625Y-804292D01*
X104173Y-803977D01*
X104800Y-803872D01*
X105583Y-804082D01*
X106131Y-804607D01*
X106288Y-805237D01*
X106210Y-805867D01*
X105896Y-806392D01*
X104330Y-807442D01*
X103625Y-808177D01*
X103155Y-809227D01*
X102998Y-810172D01*
X106288D01*
G01X109141D02*
Y-803872D01*
X112745Y-810172D01*
Y-803872D01*
G01X115520Y-810172D02*
Y-803872D01*
X117086D01*
X117713Y-804187D01*
X118183Y-804607D01*
X118575Y-805237D01*
X118888Y-805972D01*
X118966Y-807022D01*
X118888Y-808072D01*
X118575Y-808807D01*
X118183Y-809437D01*
X117713Y-809857D01*
X117086Y-810172D01*
X115520D01*
G01X128276D02*
Y-803872D01*
X130235D01*
X130861Y-804187D01*
X131253Y-804607D01*
X131410Y-805447D01*
X131253Y-806287D01*
X130783Y-806812D01*
X130235Y-807127D01*
X128276D01*
G01X130235D02*
X131410Y-810172D01*
G01X134420D02*
Y-803872D01*
X135986D01*
X136613Y-804187D01*
X137083Y-804607D01*
X137475Y-805237D01*
X137788Y-805972D01*
X137866Y-807022D01*
X137788Y-808072D01*
X137475Y-808807D01*
X137083Y-809437D01*
X136613Y-809857D01*
X135986Y-810172D01*
X134420D01*
G01X142443Y-810382D02*
X142286Y-810277D01*
Y-810067D01*
X142443Y-809962D01*
X142600Y-810067D01*
Y-810277D01*
X142443Y-810382D01*
G01X210093Y-779172D02*
Y-787172D01*
X214093D01*
G01X221893D02*
Y-781839D01*
G01Y-782772D02*
X221493Y-782239D01*
X220893Y-781972D01*
X220193Y-781839D01*
X219493Y-782105D01*
X218893Y-782639D01*
X218493Y-783439D01*
X218293Y-784505D01*
X218493Y-785572D01*
X218893Y-786372D01*
X219493Y-786905D01*
X220193Y-787172D01*
X220893Y-787039D01*
X221493Y-786639D01*
X221893Y-786106D01*
G01X225993Y-789572D02*
X226593Y-789839D01*
X227393Y-789572D01*
X227893Y-789039D01*
X228293Y-788372D01*
X228893Y-786239D01*
X230193Y-781839D01*
G01X226993D02*
X228893Y-786239D01*
G01X234593Y-783572D02*
X237793D01*
X237493Y-782639D01*
X236993Y-782105D01*
X236293Y-781839D01*
X235593Y-781972D01*
X234993Y-782372D01*
X234593Y-783305D01*
X234393Y-784106D01*
Y-784905D01*
X234593Y-785705D01*
X235093Y-786505D01*
X235693Y-787039D01*
X236393Y-787172D01*
X237093Y-786905D01*
X237793Y-786106D01*
G01X242693Y-787172D02*
Y-781839D01*
G01Y-782905D02*
X243193Y-782372D01*
X243693Y-781972D01*
X244393Y-781839D01*
X244893Y-781972D01*
X245493Y-782372D01*
G01X229193Y-829172D02*
X232993D01*
X229193Y-837172D01*
X232993D01*
G01X239093Y-831839D02*
Y-837172D01*
G01Y-829705D02*
X238893Y-829572D01*
Y-829305D01*
X239093Y-829172D01*
X239293Y-829305D01*
Y-829572D01*
X239093Y-829705D01*
G01X245793Y-834505D02*
X248393D01*
G01X253093Y-837172D02*
Y-829172D01*
X255493D01*
X256293Y-829572D01*
X256893Y-830505D01*
X257093Y-831572D01*
X256893Y-832639D01*
X256393Y-833439D01*
X255493Y-833839D01*
X253093D01*
G01X263093Y-831839D02*
Y-837172D01*
G01Y-829705D02*
X262893Y-829572D01*
Y-829305D01*
X263093Y-829172D01*
X263293Y-829305D01*
Y-829572D01*
X263093Y-829705D01*
G01X269393Y-837172D02*
Y-831839D01*
G01Y-833172D02*
X269793Y-832505D01*
X270393Y-831972D01*
X271193Y-831839D01*
X271893Y-831972D01*
X272493Y-832505D01*
X272793Y-833439D01*
Y-837172D01*
G01X277693Y-839172D02*
X278393Y-839705D01*
X279193Y-839839D01*
X279893Y-839705D01*
X280493Y-839039D01*
X280893Y-838105D01*
Y-831839D01*
G01Y-832905D02*
X280493Y-832372D01*
X279893Y-831972D01*
X279193Y-831839D01*
X278393Y-832105D01*
X277893Y-832639D01*
X277493Y-833572D01*
X277293Y-834505D01*
X277393Y-835305D01*
X277793Y-836239D01*
X278393Y-836905D01*
X279193Y-837172D01*
X279793Y-837039D01*
X280493Y-836505D01*
X280893Y-835972D01*
G01X223493Y-812172D02*
Y-804172D01*
X226093Y-810839D01*
X228693Y-804172D01*
Y-812172D01*
G01X231593D02*
X234093Y-804172D01*
X236593Y-812172D01*
G01X235693Y-809372D02*
X232493D01*
G01X239993Y-811106D02*
X240793Y-811772D01*
X241693Y-812172D01*
X242493D01*
X243293Y-811772D01*
X243893Y-811106D01*
X244193Y-810172D01*
X243993Y-809239D01*
X243493Y-808439D01*
X242593Y-807905D01*
X241393Y-807639D01*
X240693Y-807105D01*
X240393Y-806172D01*
X240593Y-805239D01*
X241093Y-804572D01*
X241793Y-804172D01*
X242493D01*
X243193Y-804439D01*
X243793Y-805105D01*
G01X247893Y-812172D02*
Y-804172D01*
G01X251693D02*
X247893Y-809106D01*
G01X252293Y-812172D02*
X249593Y-806839D01*
G01X256793Y-809505D02*
X259393D01*
G01X266093Y-804172D02*
Y-812172D01*
G01X263793Y-804172D02*
X268393D01*
G01X274093Y-812172D02*
X273293Y-812039D01*
X272593Y-811505D01*
X271993Y-810705D01*
X271593Y-809772D01*
X271393Y-808705D01*
Y-807639D01*
X271593Y-806572D01*
X271993Y-805639D01*
X272593Y-804839D01*
X273293Y-804305D01*
X274093Y-804172D01*
X274893Y-804305D01*
X275593Y-804839D01*
X276193Y-805639D01*
X276593Y-806572D01*
X276793Y-807639D01*
Y-808705D01*
X276593Y-809772D01*
X276193Y-810705D01*
X275593Y-811505D01*
X274893Y-812039D01*
X274093Y-812172D01*
G01X280093D02*
Y-804172D01*
X282493D01*
X283293Y-804572D01*
X283893Y-805505D01*
X284093Y-806572D01*
X283893Y-807639D01*
X283393Y-808439D01*
X282493Y-808839D01*
X280093D01*
G01X336693Y-830505D02*
X337293Y-829705D01*
X337993Y-829305D01*
X338793Y-829172D01*
X339793Y-829439D01*
X340493Y-830105D01*
X340693Y-830905D01*
X340593Y-831706D01*
X340193Y-832372D01*
X338193Y-833705D01*
X337293Y-834639D01*
X336693Y-835972D01*
X336493Y-837172D01*
X340693D01*
G01X346593Y-829172D02*
X345793Y-829439D01*
X345193Y-830105D01*
X344793Y-830905D01*
X344493Y-831972D01*
X344393Y-833172D01*
X344493Y-834372D01*
X344793Y-835439D01*
X345193Y-836239D01*
X345793Y-836905D01*
X346593Y-837172D01*
X347393Y-836905D01*
X347993Y-836239D01*
X348393Y-835439D01*
X348693Y-834372D01*
X348793Y-833172D01*
X348693Y-831972D01*
X348393Y-830905D01*
X347993Y-830105D01*
X347393Y-829439D01*
X346593Y-829172D01*
G01X352693Y-830505D02*
X353293Y-829705D01*
X353993Y-829305D01*
X354793Y-829172D01*
X355793Y-829439D01*
X356493Y-830105D01*
X356693Y-830905D01*
X356593Y-831706D01*
X356193Y-832372D01*
X354193Y-833705D01*
X353293Y-834639D01*
X352693Y-835972D01*
X352493Y-837172D01*
X356693D01*
G01X360693Y-830505D02*
X361293Y-829705D01*
X361993Y-829305D01*
X362793Y-829172D01*
X363793Y-829439D01*
X364493Y-830105D01*
X364693Y-830905D01*
X364593Y-831706D01*
X364193Y-832372D01*
X362193Y-833705D01*
X361293Y-834639D01*
X360693Y-835972D01*
X360493Y-837172D01*
X364693D01*
G01X368793Y-837439D02*
X372393Y-829172D01*
G01X378593Y-837172D02*
Y-829172D01*
X377393Y-830772D01*
G01Y-837172D02*
X379793D01*
G01X384693Y-830505D02*
X385293Y-829705D01*
X385993Y-829305D01*
X386793Y-829172D01*
X387793Y-829439D01*
X388493Y-830105D01*
X388693Y-830905D01*
X388593Y-831706D01*
X388193Y-832372D01*
X386193Y-833705D01*
X385293Y-834639D01*
X384693Y-835972D01*
X384493Y-837172D01*
X388693D01*
G01X392793Y-837439D02*
X396393Y-829172D01*
G01X402593D02*
X401793Y-829439D01*
X401193Y-830105D01*
X400793Y-830905D01*
X400493Y-831972D01*
X400393Y-833172D01*
X400493Y-834372D01*
X400793Y-835439D01*
X401193Y-836239D01*
X401793Y-836905D01*
X402593Y-837172D01*
X403393Y-836905D01*
X403993Y-836239D01*
X404393Y-835439D01*
X404693Y-834372D01*
X404793Y-833172D01*
X404693Y-831972D01*
X404393Y-830905D01*
X403993Y-830105D01*
X403393Y-829439D01*
X402593Y-829172D01*
G01X408693Y-830505D02*
X409293Y-829705D01*
X409993Y-829305D01*
X410793Y-829172D01*
X411793Y-829439D01*
X412493Y-830105D01*
X412693Y-830905D01*
X412593Y-831706D01*
X412193Y-832372D01*
X410193Y-833705D01*
X409293Y-834639D01*
X408693Y-835972D01*
X408493Y-837172D01*
X412693D01*
G01X336393Y-814672D02*
Y-806672D01*
X338393D01*
X339193Y-807072D01*
X339793Y-807605D01*
X340293Y-808405D01*
X340693Y-809339D01*
X340793Y-810672D01*
X340693Y-812005D01*
X340293Y-812939D01*
X339793Y-813739D01*
X339193Y-814272D01*
X338393Y-814672D01*
X336393D01*
G01X344093D02*
X346593Y-806672D01*
X349093Y-814672D01*
G01X348193Y-811872D02*
X344993D01*
G01X354593Y-806672D02*
X353793Y-806939D01*
X353193Y-807605D01*
X352793Y-808405D01*
X352493Y-809472D01*
X352393Y-810672D01*
X352493Y-811872D01*
X352793Y-812939D01*
X353193Y-813739D01*
X353793Y-814405D01*
X354593Y-814672D01*
X355393Y-814405D01*
X355993Y-813739D01*
X356393Y-812939D01*
X356693Y-811872D01*
X356793Y-810672D01*
X356693Y-809472D01*
X356393Y-808405D01*
X355993Y-807605D01*
X355393Y-806939D01*
X354593Y-806672D01*
G01X360693Y-814672D02*
Y-806672D01*
X364493D01*
G01X363093Y-810539D02*
X360693D01*
G01X370593Y-806672D02*
X369793Y-806939D01*
X369193Y-807605D01*
X368793Y-808405D01*
X368493Y-809472D01*
X368393Y-810672D01*
X368493Y-811872D01*
X368793Y-812939D01*
X369193Y-813739D01*
X369793Y-814405D01*
X370593Y-814672D01*
X371393Y-814405D01*
X371993Y-813739D01*
X372393Y-812939D01*
X372693Y-811872D01*
X372793Y-810672D01*
X372693Y-809472D01*
X372393Y-808405D01*
X371993Y-807605D01*
X371393Y-806939D01*
X370593Y-806672D01*
G01X378593D02*
Y-814672D01*
G01X376293Y-806672D02*
X380893D01*
G01X384593Y-814672D02*
Y-806672D01*
X386993D01*
X387793Y-807072D01*
X388393Y-808005D01*
X388593Y-809072D01*
X388393Y-810139D01*
X387893Y-810939D01*
X386993Y-811339D01*
X384593D01*
G01X395393Y-810405D02*
X395793Y-810005D01*
X396093Y-809339D01*
X396293Y-808405D01*
X396093Y-807605D01*
X395693Y-807072D01*
X394993Y-806672D01*
X392293D01*
Y-814672D01*
X395593D01*
X396293Y-814139D01*
X396693Y-813339D01*
X396893Y-812405D01*
X396693Y-811472D01*
X396093Y-810672D01*
X395393Y-810405D01*
X392293D01*
G01X400093Y-814672D02*
X402593Y-806672D01*
X405093Y-814672D01*
G01X404193Y-811872D02*
X400993D01*
G01X408693Y-814672D02*
Y-806672D01*
X412493D01*
G01X411093Y-810539D02*
X408693D01*
G01X418593Y-806672D02*
X417793Y-806939D01*
X417193Y-807605D01*
X416793Y-808405D01*
X416493Y-809472D01*
X416393Y-810672D01*
X416493Y-811872D01*
X416793Y-812939D01*
X417193Y-813739D01*
X417793Y-814405D01*
X418593Y-814672D01*
X419393Y-814405D01*
X419993Y-813739D01*
X420393Y-812939D01*
X420693Y-811872D01*
X420793Y-810672D01*
X420693Y-809472D01*
X420393Y-808405D01*
X419993Y-807605D01*
X419393Y-806939D01*
X418593Y-806672D01*
G01X356693Y-787172D02*
Y-779172D01*
X360493D01*
G01X359093Y-783039D02*
X356693D01*
G01X366593Y-779172D02*
X365793Y-779439D01*
X365193Y-780105D01*
X364793Y-780905D01*
X364493Y-781972D01*
X364393Y-783172D01*
X364493Y-784372D01*
X364793Y-785439D01*
X365193Y-786239D01*
X365793Y-786905D01*
X366593Y-787172D01*
X367393Y-786905D01*
X367993Y-786239D01*
X368393Y-785439D01*
X368693Y-784372D01*
X368793Y-783172D01*
X368693Y-781972D01*
X368393Y-780905D01*
X367993Y-780105D01*
X367393Y-779439D01*
X366593Y-779172D01*
G01X374593D02*
Y-787172D01*
G01X372293Y-779172D02*
X376893D01*
G01X379593Y-789839D02*
X385593D01*
G01X388593Y-787172D02*
Y-779172D01*
X390993D01*
X391793Y-779572D01*
X392393Y-780505D01*
X392593Y-781572D01*
X392393Y-782639D01*
X391893Y-783439D01*
X390993Y-783839D01*
X388593D01*
G01X396393Y-787172D02*
Y-779172D01*
X398393D01*
X399193Y-779572D01*
X399793Y-780105D01*
X400293Y-780905D01*
X400693Y-781839D01*
X400793Y-783172D01*
X400693Y-784505D01*
X400293Y-785439D01*
X399793Y-786239D01*
X399193Y-786772D01*
X398393Y-787172D01*
X396393D01*
G01X407393Y-782905D02*
X407793Y-782505D01*
X408093Y-781839D01*
X408293Y-780905D01*
X408093Y-780105D01*
X407693Y-779572D01*
X406993Y-779172D01*
X404293D01*
Y-787172D01*
X407593D01*
X408293Y-786639D01*
X408693Y-785839D01*
X408893Y-784905D01*
X408693Y-783972D01*
X408093Y-783172D01*
X407393Y-782905D01*
X404293D01*
G01X411593Y-789839D02*
X417593D01*
G01X424793Y-779839D02*
X424193Y-779439D01*
X423493Y-779172D01*
X422693D01*
X421793Y-779572D01*
X421093Y-780239D01*
X420593Y-781039D01*
X420193Y-782372D01*
X420093Y-783572D01*
X420293Y-784772D01*
X420593Y-785572D01*
X421193Y-786372D01*
X421893Y-786905D01*
X422593Y-787172D01*
X423293D01*
X423993Y-786905D01*
X424593Y-786505D01*
X425093Y-785972D01*
G01X430593Y-787172D02*
X429793Y-787039D01*
X429093Y-786505D01*
X428493Y-785705D01*
X428093Y-784772D01*
X427893Y-783705D01*
Y-782639D01*
X428093Y-781572D01*
X428493Y-780639D01*
X429093Y-779839D01*
X429793Y-779305D01*
X430593Y-779172D01*
X431393Y-779305D01*
X432093Y-779839D01*
X432693Y-780639D01*
X433093Y-781572D01*
X433293Y-782639D01*
Y-783705D01*
X433093Y-784772D01*
X432693Y-785705D01*
X432093Y-786505D01*
X431393Y-787039D01*
X430593Y-787172D01*
G01X436293D02*
Y-779172D01*
X440893Y-787172D01*
Y-779172D01*
G01X444093D02*
X446593Y-787172D01*
X449093Y-779172D01*
G01X456593Y-787172D02*
X452593D01*
Y-779172D01*
X456593D01*
G01X454993Y-783039D02*
X452593D01*
G01X460593Y-787172D02*
Y-779172D01*
X463093D01*
X463893Y-779572D01*
X464393Y-780105D01*
X464593Y-781172D01*
X464393Y-782239D01*
X463793Y-782905D01*
X463093Y-783305D01*
X460593D01*
G01X463093D02*
X464593Y-787172D01*
G01X470593Y-779172D02*
Y-787172D01*
G01X468293Y-779172D02*
X472893D01*
G01X480593Y-787172D02*
X476593D01*
Y-779172D01*
X480593D01*
G01X478993Y-783039D02*
X476593D01*
G01X484593Y-787172D02*
Y-779172D01*
X487093D01*
X487893Y-779572D01*
X488393Y-780105D01*
X488593Y-781172D01*
X488393Y-782239D01*
X487793Y-782905D01*
X487093Y-783305D01*
X484593D01*
G01X487093D02*
X488593Y-787172D01*
G01X425093Y-840172D02*
Y-832172D01*
X423893Y-833772D01*
G01Y-840172D02*
X426293D01*
G01X431193Y-836839D02*
X431893Y-835905D01*
X432493Y-835372D01*
X433293Y-835105D01*
X433993Y-835372D01*
X434493Y-835905D01*
X434893Y-836705D01*
X434993Y-837639D01*
X434893Y-838439D01*
X434493Y-839239D01*
X433893Y-839905D01*
X433193Y-840172D01*
X432393Y-839905D01*
X431693Y-839106D01*
X431293Y-837905D01*
X431193Y-836572D01*
X431393Y-834839D01*
X431693Y-833905D01*
X432193Y-832972D01*
X432893Y-832305D01*
X433593Y-832172D01*
X434293Y-832439D01*
X434793Y-833105D01*
G01X441093Y-840439D02*
X440893Y-840305D01*
Y-840039D01*
X441093Y-839905D01*
X441293Y-840039D01*
Y-840305D01*
X441093Y-840439D01*
G01X447193Y-836839D02*
X447893Y-835905D01*
X448493Y-835372D01*
X449293Y-835105D01*
X449993Y-835372D01*
X450493Y-835905D01*
X450893Y-836705D01*
X450993Y-837639D01*
X450893Y-838439D01*
X450493Y-839239D01*
X449893Y-839905D01*
X449193Y-840172D01*
X448393Y-839905D01*
X447693Y-839106D01*
X447293Y-837905D01*
X447193Y-836572D01*
X447393Y-834839D01*
X447693Y-833905D01*
X448193Y-832972D01*
X448893Y-832305D01*
X449593Y-832172D01*
X450293Y-832439D01*
X450793Y-833105D01*
G01X470093Y-840172D02*
Y-832172D01*
X468893Y-833772D01*
G01Y-840172D02*
X471293D01*
G01X477893D02*
X478093Y-838439D01*
X478393Y-836972D01*
X478793Y-835639D01*
X479293Y-834172D01*
X480093Y-832172D01*
X476093D01*
G01X486093Y-840439D02*
X485893Y-840305D01*
Y-840039D01*
X486093Y-839905D01*
X486293Y-840039D01*
Y-840305D01*
X486093Y-840439D01*
G01X492193Y-833505D02*
X492793Y-832705D01*
X493493Y-832305D01*
X494293Y-832172D01*
X495293Y-832439D01*
X495993Y-833105D01*
X496193Y-833905D01*
X496093Y-834706D01*
X495693Y-835372D01*
X493693Y-836705D01*
X492793Y-837639D01*
X492193Y-838972D01*
X491993Y-840172D01*
X496193D01*
G01X490193Y-815172D02*
Y-807172D01*
X493993D01*
G01X492593Y-811039D02*
X490193D01*
G54D79*
X1025168Y153909D03*
Y155877D03*
Y157846D03*
Y159814D03*
Y161783D03*
Y169657D03*
Y171625D03*
X1051940Y159814D03*
Y157846D03*
Y155877D03*
Y153909D03*
Y171625D03*
Y169657D03*
Y167688D03*
Y165720D03*
Y163751D03*
Y161783D03*
G54D88*
X1119268Y153119D03*
X1121238D03*
X1123208D03*
X1125178D03*
X1127148D03*
X1129118D03*
X1131088D03*
Y180279D03*
X1129118D03*
X1127148D03*
X1125178D03*
X1123208D03*
X1121238D03*
X1119268D03*
X1136988Y153119D03*
X1138958D03*
X1140928D03*
X1142898D03*
X1144868D03*
Y180279D03*
X1142898D03*
X1140928D03*
X1138958D03*
X1136988D03*
G54D89*
X1240158Y57480D03*
Y521260D03*
M02*
